(kicad_pcb
	(version 20241229)
	(generator "pcbnew")
	(generator_version "9.0")
	(general
		(thickness 1.552)
		(legacy_teardrops no)
	)
	(paper "A4")
	(title_block
		(date "2023-07-25")
		(rev "1.1.4")
		(comment 9 "footprints 359-363 of 379")
	)
	(layers
		(0 "F.Cu" signal)
		(4 "In1.Cu" signal)
		(6 "In2.Cu" signal)
		(8 "In3.Cu" signal)
		(10 "In4.Cu" signal)
		(12 "In5.Cu" signal)
		(14 "In6.Cu" signal)
		(2 "B.Cu" signal)
		(9 "F.Adhes" user "F.Adhesive")
		(11 "B.Adhes" user "B.Adhesive")
		(13 "F.Paste" user)
		(15 "B.Paste" user)
		(5 "F.SilkS" user "F.Silkscreen")
		(7 "B.SilkS" user "B.Silkscreen")
		(1 "F.Mask" user)
		(3 "B.Mask" user)
		(17 "Dwgs.User" user "User.Drawings")
		(19 "Cmts.User" user "User.Comments")
		(21 "Eco1.User" user "User.Eco1")
		(23 "Eco2.User" user "User.Eco2")
		(25 "Edge.Cuts" user)
		(27 "Margin" user)
		(31 "F.CrtYd" user "F.Courtyard")
		(29 "B.CrtYd" user "B.Courtyard")
		(35 "F.Fab" user)
		(33 "B.Fab" user)
	)
	(footprint "antmicro-footprints:C_0402_1005Metric"
		(layer "B.Cu")
		(at 144.2 81.5 90)
		(descr "Capacitor SMD 0402")
		(tags "capacitor SMD 0402")
		(property "Reference" "C117"
			(at 0.96 0.33 90)
			(layer "B.SilkS")
			(effects
				(font
					(size 0.65 0.65)
					(thickness 0.15)
				)
				(justify right bottom mirror)
			)
		)
		(property "Value" "C_47p_0402"
			(at 0 -1.4 90)
			(layer "B.Fab")
			(hide yes)
			(effects
				(font
					(size 0.7 0.7)
					(thickness 0.15)
				)
				(justify right bottom mirror)
			)
		)
		(property "Datasheet" "https://www.kemet.com/en/us/capacitors/product/C0402C470J5GACTU.html"
			(at 0 0 90)
			(layer "F.Fab")
			(hide yes)
			(effects
				(font
					(size 1.27 1.27)
					(thickness 0.15)
				)
			)
		)
		(property "Description" "SMD Multilayer Ceramic Capacitor, 47 pF, 50 V, 0402 [1005 Metric], ± 5%, C0G / NP0, C Series KEMET"
			(at 0 0 90)
			(layer "F.Fab")
			(hide yes)
			(effects
				(font
					(size 1.27 1.27)
					(thickness 0.15)
				)
			)
		)
		(property "Author" "Antmicro"
			(at 225.7 -62.7 0)
			(layer "B.Fab")
			(hide yes)
			(effects
				(font
					(size 1 1)
					(thickness 0.15)
				)
				(justify mirror)
			)
		)
		(property "Dielectric" "C0G"
			(at 225.7 -62.7 0)
			(layer "B.Fab")
			(hide yes)
			(effects
				(font
					(size 1 1)
					(thickness 0.15)
				)
				(justify mirror)
			)
		)
		(property "License" "Apache-2.0"
			(at 225.7 -62.7 0)
			(layer "B.Fab")
			(hide yes)
			(effects
				(font
					(size 1 1)
					(thickness 0.15)
				)
				(justify mirror)
			)
		)
		(property "MPN" "C0402C470J5GACTU"
			(at 225.7 -62.7 0)
			(layer "B.Fab")
			(hide yes)
			(effects
				(font
					(size 1 1)
					(thickness 0.15)
				)
				(justify mirror)
			)
		)
		(property "Manufacturer" "KEMET"
			(at 225.7 -62.7 0)
			(layer "B.Fab")
			(hide yes)
			(effects
				(font
					(size 1 1)
					(thickness 0.15)
				)
				(justify mirror)
			)
		)
		(property "Val" "47p"
			(at 225.7 -62.7 0)
			(layer "B.Fab")
			(hide yes)
			(effects
				(font
					(size 1 1)
					(thickness 0.15)
				)
				(justify mirror)
			)
		)
		(property "Voltage" ""
			(at 225.7 -62.7 0)
			(layer "B.Fab")
			(hide yes)
			(effects
				(font
					(size 1 1)
					(thickness 0.15)
				)
				(justify mirror)
			)
		)
		(sheetname "/Peripherals/")
		(sheetfile "peripherals.kicad_sch")
		(attr smd)
		(fp_rect
			(start -0.925 0.47)
			(end 0.925 -0.47)
			(stroke
				(width 0.05)
				(type default)
			)
			(fill no)
			(layer "B.CrtYd")
		)
		(fp_line
			(start 0.504 -0.248)
			(end -0.494 -0.248)
			(stroke
				(width 0.15)
				(type solid)
			)
			(layer "B.Fab")
		)
		(fp_line
			(start -0.494 -0.248)
			(end -0.494 0.25)
			(stroke
				(width 0.15)
				(type solid)
			)
			(layer "B.Fab")
		)
		(fp_line
			(start 0.504 0.25)
			(end 0.504 -0.248)
			(stroke
				(width 0.15)
				(type solid)
			)
			(layer "B.Fab")
		)
		(fp_line
			(start -0.494 0.25)
			(end 0.504 0.25)
			(stroke
				(width 0.15)
				(type solid)
			)
			(layer "B.Fab")
		)
		(fp_text user "Author: Antmicro"
			(at -0.939 -3.399 270)
			(layer "B.Fab")
			(effects
				(font
					(size 0.7 0.7)
					(thickness 0.15)
				)
				(justify left bottom mirror)
			)
		)
		(fp_text user "${REFERENCE}"
			(at -0.939 -4.599 270)
			(layer "B.Fab")
			(effects
				(font
					(size 0.7 0.7)
					(thickness 0.15)
				)
				(justify left bottom mirror)
			)
		)
		(fp_text user "License: Apache-2.0"
			(at -0.939 -5.799 270)
			(layer "B.Fab")
			(effects
				(font
					(size 0.7 0.7)
					(thickness 0.15)
				)
				(justify left bottom mirror)
			)
		)
		(pad "1" smd roundrect
			(at -0.48 0 90)
			(size 0.59 0.64)
			(layers "B.Cu" "B.Mask" "B.Paste")
			(roundrect_rratio 0.25)
			(net 1 "GND")
			(pintype "passive")
		)
		(pad "2" smd roundrect
			(at 0.48 0 90)
			(size 0.59 0.64)
			(layers "B.Cu" "B.Mask" "B.Paste")
			(roundrect_rratio 0.25)
			(net 359 "/Peripherals/USB_DP")
			(pintype "passive")
		)
	)
	(footprint "antmicro-footprints:R_0402_1005Metric"
		(layer "B.Cu")
		(at 139.23 59.2 -90)
		(descr "Resistor SMD 0402")
		(tags "resistor SMD 0402")
		(property "Reference" "R7"
			(at -0.76 -1.3 90)
			(layer "B.SilkS")
			(effects
				(font
					(size 0.65 0.65)
					(thickness 0.15)
				)
				(justify left bottom mirror)
			)
		)
		(property "Value" "R_22R_0402"
			(at 0 -1.4 90)
			(layer "B.Fab")
			(hide yes)
			(effects
				(font
					(size 0.7 0.7)
					(thickness 0.15)
				)
				(justify left bottom mirror)
			)
		)
		(property "Datasheet" "https://www.bourns.com/docs/product-datasheets/cr.pdf"
			(at 0 0 270)
			(layer "F.Fab")
			(hide yes)
			(effects
				(font
					(size 1.27 1.27)
					(thickness 0.15)
				)
			)
		)
		(property "Description" "SMD Chip Resistor, 22 ohm, ± 1%, 62.5 mW, 0402 [1005 Metric], Thick Film, General Purpose"
			(at 0 0 270)
			(layer "F.Fab")
			(hide yes)
			(effects
				(font
					(size 1.27 1.27)
					(thickness 0.15)
				)
			)
		)
		(property "Author" "Antmicro"
			(at 80.03 198.43 0)
			(layer "B.Fab")
			(hide yes)
			(effects
				(font
					(size 1 1)
					(thickness 0.15)
				)
				(justify mirror)
			)
		)
		(property "License" "Apache-2.0"
			(at 80.03 198.43 0)
			(layer "B.Fab")
			(hide yes)
			(effects
				(font
					(size 1 1)
					(thickness 0.15)
				)
				(justify mirror)
			)
		)
		(property "MPN" "CR0402-FX-22R0GLF"
			(at 80.03 198.43 0)
			(layer "B.Fab")
			(hide yes)
			(effects
				(font
					(size 1 1)
					(thickness 0.15)
				)
				(justify mirror)
			)
		)
		(property "Manufacturer" "Bourns"
			(at 80.03 198.43 0)
			(layer "B.Fab")
			(hide yes)
			(effects
				(font
					(size 1 1)
					(thickness 0.15)
				)
				(justify mirror)
			)
		)
		(property "Tolerance" "1%"
			(at 80.03 198.43 0)
			(layer "B.Fab")
			(hide yes)
			(effects
				(font
					(size 1 1)
					(thickness 0.15)
				)
				(justify mirror)
			)
		)
		(property "Val" "22R"
			(at 80.03 198.43 0)
			(layer "B.Fab")
			(hide yes)
			(effects
				(font
					(size 1 1)
					(thickness 0.15)
				)
				(justify mirror)
			)
		)
		(sheetname "/Power Supply/")
		(sheetfile "supply.kicad_sch")
		(attr smd)
		(fp_rect
			(start -0.925 0.47)
			(end 0.925 -0.47)
			(stroke
				(width 0.05)
				(type default)
			)
			(fill no)
			(layer "B.CrtYd")
		)
		(fp_rect
			(start -0.5 0.25)
			(end 0.5 -0.25)
			(stroke
				(width 0.15)
				(type solid)
			)
			(fill no)
			(layer "B.Fab")
		)
		(fp_text user "${REFERENCE}"
			(at -0.95 -3.168 90)
			(layer "B.Fab")
			(effects
				(font
					(size 0.7 0.7)
					(thickness 0.15)
				)
				(justify left bottom mirror)
			)
		)
		(fp_text user "Author: Antmicro"
			(at -0.95 -4.169 90)
			(layer "B.Fab")
			(effects
				(font
					(size 0.7 0.7)
					(thickness 0.15)
				)
				(justify left bottom mirror)
			)
		)
		(fp_text user "License: Apache-2.0"
			(at -0.95 -5.169 90)
			(layer "B.Fab")
			(effects
				(font
					(size 0.7 0.7)
					(thickness 0.15)
				)
				(justify left bottom mirror)
			)
		)
		(pad "1" smd roundrect
			(at -0.48 0 270)
			(size 0.59 0.64)
			(layers "B.Cu" "B.Mask" "B.Paste")
			(roundrect_rratio 0.25)
			(net 30 "Net-(U1-REF)")
			(pintype "passive")
		)
		(pad "2" smd roundrect
			(at 0.48 0 270)
			(size 0.59 0.64)
			(layers "B.Cu" "B.Mask" "B.Paste")
			(roundrect_rratio 0.25)
			(net 248 "+1V5")
			(pintype "passive")
		)
	)
	(footprint "antmicro-footprints:C_0201"
		(layer "B.Cu")
		(at 124.7 88.7 -90)
		(descr "Capacitor SMD 0201")
		(tags "capacitor SMD 0201")
		(property "Reference" "C106"
			(at -14.095736 9.07 90)
			(layer "B.SilkS")
			(effects
				(font
					(size 0.65 0.65)
					(thickness 0.15)
				)
				(justify left bottom mirror)
			)
		)
		(property "Value" "C_100n_0201"
			(at 0 -1.4 90)
			(layer "B.Fab")
			(hide yes)
			(effects
				(font
					(size 0.7 0.7)
					(thickness 0.15)
				)
				(justify left bottom mirror)
			)
		)
		(property "Datasheet" "https://www.yageo.com/en/Chart/Download/pdf/CC0201KRX6S5BB104"
			(at 0 0 270)
			(layer "F.Fab")
			(hide yes)
			(effects
				(font
					(size 1.27 1.27)
					(thickness 0.15)
				)
			)
		)
		(property "Description" "SMD Multilayer Ceramic Capacitor, 0.1 µF, 6.3 V, 0201 [0603 Metric], ± 10%, X6S, CC Series"
			(at 0 0 270)
			(layer "F.Fab")
			(hide yes)
			(effects
				(font
					(size 1.27 1.27)
					(thickness 0.15)
				)
			)
		)
		(property "Author" "Antmicro"
			(at 36 213.4 0)
			(layer "B.Fab")
			(hide yes)
			(effects
				(font
					(size 1 1)
					(thickness 0.15)
				)
				(justify mirror)
			)
		)
		(property "Dielectric" ""
			(at 36 213.4 0)
			(layer "B.Fab")
			(hide yes)
			(effects
				(font
					(size 1 1)
					(thickness 0.15)
				)
				(justify mirror)
			)
		)
		(property "License" "Apache-2.0"
			(at 36 213.4 0)
			(layer "B.Fab")
			(hide yes)
			(effects
				(font
					(size 1 1)
					(thickness 0.15)
				)
				(justify mirror)
			)
		)
		(property "MPN" "CC0201KRX6S5BB104"
			(at 36 213.4 0)
			(layer "B.Fab")
			(hide yes)
			(effects
				(font
					(size 1 1)
					(thickness 0.15)
				)
				(justify mirror)
			)
		)
		(property "Manufacturer" "YAGEO"
			(at 36 213.4 0)
			(layer "B.Fab")
			(hide yes)
			(effects
				(font
					(size 1 1)
					(thickness 0.15)
				)
				(justify mirror)
			)
		)
		(property "Val" "100n"
			(at 36 213.4 0)
			(layer "B.Fab")
			(hide yes)
			(effects
				(font
					(size 1 1)
					(thickness 0.15)
				)
				(justify mirror)
			)
		)
		(property "Voltage" ""
			(at 36 213.4 0)
			(layer "B.Fab")
			(hide yes)
			(effects
				(font
					(size 1 1)
					(thickness 0.15)
				)
				(justify mirror)
			)
		)
		(property "Public" "False"
			(at 0 0 270)
			(unlocked yes)
			(layer "B.Fab")
			(hide yes)
			(effects
				(font
					(size 1 1)
					(thickness 0.15)
				)
				(justify mirror)
			)
		)
		(sheetname "/FPGA Power/")
		(sheetfile "FPGA_Power.kicad_sch")
		(attr smd)
		(fp_rect
			(start -0.7 0.35)
			(end 0.7 -0.35)
			(stroke
				(width 0.05)
				(type default)
			)
			(fill no)
			(layer "B.CrtYd")
		)
		(fp_rect
			(start 0.3 -0.15)
			(end -0.301 0.149)
			(stroke
				(width 0.15)
				(type solid)
			)
			(fill no)
			(layer "B.Fab")
		)
		(fp_text user "Author: Antmicro"
			(at -0.72 -5.4 90)
			(layer "B.Fab")
			(effects
				(font
					(size 0.7 0.7)
					(thickness 0.15)
				)
				(justify left bottom mirror)
			)
		)
		(fp_text user "License: Apache-2.0"
			(at -0.72 -4.4 90)
			(layer "B.Fab")
			(effects
				(font
					(size 0.7 0.7)
					(thickness 0.15)
				)
				(justify left bottom mirror)
			)
		)
		(fp_text user "${REFERENCE}"
			(at -0.72 -3.4 90)
			(layer "B.Fab")
			(effects
				(font
					(size 0.7 0.7)
					(thickness 0.15)
				)
				(justify left bottom mirror)
			)
		)
		(pad "" smd roundrect
			(at -0.349 0.002 270)
			(size 0.318 0.36)
			(layers "B.Paste")
			(roundrect_rratio 0.25)
		)
		(pad "" smd roundrect
			(at 0.341 0.002 270)
			(size 0.318 0.36)
			(layers "B.Paste")
			(roundrect_rratio 0.25)
		)
		(pad "1" smd roundrect
			(at -0.321 0.002 270)
			(size 0.46 0.4)
			(layers "B.Cu" "B.Mask")
			(roundrect_rratio 0.25)
			(net 1 "GND")
			(pintype "passive")
		)
		(pad "2" smd roundrect
			(at 0.32 0.002 270)
			(size 0.46 0.4)
			(layers "B.Cu" "B.Mask")
			(roundrect_rratio 0.25)
			(net 9 "/FPGA Power/VCC_AUX")
			(pintype "passive")
		)
	)
	(footprint "antmicro-footprints:TP_SMD_0.75mm"
		(layer "B.Cu")
		(at 96.94 88.2 90)
		(property "Reference" "TP32"
			(at 0.76 0.39 90)
			(layer "B.SilkS")
			(effects
				(font
					(size 0.65 0.65)
					(thickness 0.15)
				)
				(justify right bottom mirror)
			)
		)
		(property "Value" "TP_0.75mm_SMD"
			(at 0 -1.2 90)
			(layer "B.Fab")
			(hide yes)
			(effects
				(font
					(size 0.7 0.7)
					(thickness 0.15)
				)
				(justify right bottom mirror)
			)
		)
		(property "Description" "SMT test point"
			(at 0 0 90)
			(layer "F.Fab")
			(hide yes)
			(effects
				(font
					(size 1.27 1.27)
					(thickness 0.15)
				)
			)
		)
		(property "Author" "Antmicro"
			(at 185.14 -8.74 0)
			(layer "B.Fab")
			(hide yes)
			(effects
				(font
					(size 1 1)
					(thickness 0.15)
				)
				(justify mirror)
			)
		)
		(property "License" "Apache-2.0"
			(at 185.14 -8.74 0)
			(layer "B.Fab")
			(hide yes)
			(effects
				(font
					(size 1 1)
					(thickness 0.15)
				)
				(justify mirror)
			)
		)
		(property "MPN" ""
			(at 185.14 -8.74 0)
			(layer "B.Fab")
			(hide yes)
			(effects
				(font
					(size 1 1)
					(thickness 0.15)
				)
				(justify mirror)
			)
		)
		(property "Manufacturer" ""
			(at 185.14 -8.74 0)
			(layer "B.Fab")
			(hide yes)
			(effects
				(font
					(size 1 1)
					(thickness 0.15)
				)
				(justify mirror)
			)
		)
		(sheetname "/SDI/")
		(sheetfile "sdi.kicad_sch")
		(attr exclude_from_pos_files)
		(fp_circle
			(center 0 0)
			(end 0.475 0)
			(stroke
				(width 0.05)
				(type default)
			)
			(fill no)
			(layer "B.CrtYd")
		)
		(fp_text user "License: Apache-2.0"
			(at -0.4 -5.101 270)
			(layer "B.Fab")
			(effects
				(font
					(size 0.7 0.7)
					(thickness 0.15)
				)
				(justify left bottom mirror)
			)
		)
		(fp_text user "Author: Antmicro"
			(at -0.4 -3.901 270)
			(layer "B.Fab")
			(effects
				(font
					(size 0.7 0.7)
					(thickness 0.15)
				)
				(justify left bottom mirror)
			)
		)
		(fp_text user "${REFERENCE}"
			(at -0.4 -2.7 270)
			(layer "B.Fab")
			(effects
				(font
					(size 0.7 0.7)
					(thickness 0.15)
				)
				(justify left bottom mirror)
			)
		)
		(pad "1" smd circle
			(at 0 0 90)
			(size 0.75 0.75)
			(layers "B.Cu" "B.Mask")
			(net 178 "/SDI/~{CS_TMS}")
			(pinfunction "1")
			(pintype "passive")
		)
	)
	(footprint "antmicro-footprints:C_0402_1005Metric"
		(layer "B.Cu")
		(at 97.15 79.92 90)
		(descr "Capacitor SMD 0402")
		(tags "capacitor SMD 0402")
		(property "Reference" "C68"
			(at -1.02 1.28 90)
			(layer "B.SilkS")
			(effects
				(font
					(size 0.65 0.65)
					(thickness 0.15)
				)
				(justify right bottom mirror)
			)
		)
		(property "Value" "C_100n_0402"
			(at 0 -1.4 90)
			(layer "B.Fab")
			(hide yes)
			(effects
				(font
					(size 0.7 0.7)
					(thickness 0.15)
				)
				(justify right bottom mirror)
			)
		)
		(property "Datasheet" "https://www.murata.com/products/productdetail?partno=GRM155R61H104KE14%23"
			(at 0 0 90)
			(layer "F.Fab")
			(hide yes)
			(effects
				(font
					(size 1.27 1.27)
					(thickness 0.15)
				)
			)
		)
		(property "Description" "SMD Multilayer Ceramic Capacitor, 0.1 µF, 50 V, 0402 [1005 Metric], ± 10%, X5R, GRM Series"
			(at 0 0 90)
			(layer "F.Fab")
			(hide yes)
			(effects
				(font
					(size 1.27 1.27)
					(thickness 0.15)
				)
			)
		)
		(property "Author" "Antmicro"
			(at 177.07 -17.23 0)
			(layer "B.Fab")
			(hide yes)
			(effects
				(font
					(size 1 1)
					(thickness 0.15)
				)
				(justify mirror)
			)
		)
		(property "Dielectric" "X5R"
			(at 177.07 -17.23 0)
			(layer "B.Fab")
			(hide yes)
			(effects
				(font
					(size 1 1)
					(thickness 0.15)
				)
				(justify mirror)
			)
		)
		(property "License" "Apache-2.0"
			(at 177.07 -17.23 0)
			(layer "B.Fab")
			(hide yes)
			(effects
				(font
					(size 1 1)
					(thickness 0.15)
				)
				(justify mirror)
			)
		)
		(property "MPN" "GRM155R61H104KE14D"
			(at 177.07 -17.23 0)
			(layer "B.Fab")
			(hide yes)
			(effects
				(font
					(size 1 1)
					(thickness 0.15)
				)
				(justify mirror)
			)
		)
		(property "Manufacturer" "Murata"
			(at 177.07 -17.23 0)
			(layer "B.Fab")
			(hide yes)
			(effects
				(font
					(size 1 1)
					(thickness 0.15)
				)
				(justify mirror)
			)
		)
		(property "Val" "100n"
			(at 177.07 -17.23 0)
			(layer "B.Fab")
			(hide yes)
			(effects
				(font
					(size 1 1)
					(thickness 0.15)
				)
				(justify mirror)
			)
		)
		(property "Voltage" "50V"
			(at 177.07 -17.23 0)
			(layer "B.Fab")
			(hide yes)
			(effects
				(font
					(size 1 1)
					(thickness 0.15)
				)
				(justify mirror)
			)
		)
		(sheetname "/SDI/")
		(sheetfile "sdi.kicad_sch")
		(attr smd)
		(fp_rect
			(start -0.925 0.47)
			(end 0.925 -0.47)
			(stroke
				(width 0.05)
				(type default)
			)
			(fill no)
			(layer "B.CrtYd")
		)
		(fp_line
			(start 0.504 -0.248)
			(end -0.494 -0.248)
			(stroke
				(width 0.15)
				(type solid)
			)
			(layer "B.Fab")
		)
		(fp_line
			(start -0.494 -0.248)
			(end -0.494 0.25)
			(stroke
				(width 0.15)
				(type solid)
			)
			(layer "B.Fab")
		)
		(fp_line
			(start 0.504 0.25)
			(end 0.504 -0.248)
			(stroke
				(width 0.15)
				(type solid)
			)
			(layer "B.Fab")
		)
		(fp_line
			(start -0.494 0.25)
			(end 0.504 0.25)
			(stroke
				(width 0.15)
				(type solid)
			)
			(layer "B.Fab")
		)
		(fp_text user "${REFERENCE}"
			(at -0.939 -4.599 270)
			(layer "B.Fab")
			(effects
				(font
					(size 0.7 0.7)
					(thickness 0.15)
				)
				(justify left bottom mirror)
			)
		)
		(fp_text user "Author: Antmicro"
			(at -0.939 -3.399 270)
			(layer "B.Fab")
			(effects
				(font
					(size 0.7 0.7)
					(thickness 0.15)
				)
				(justify left bottom mirror)
			)
		)
		(fp_text user "License: Apache-2.0"
			(at -0.939 -5.799 270)
			(layer "B.Fab")
			(effects
				(font
					(size 0.7 0.7)
					(thickness 0.15)
				)
				(justify left bottom mirror)
			)
		)
		(pad "1" smd roundrect
			(at -0.48 0 90)
			(size 0.59 0.64)
			(layers "B.Cu" "B.Mask" "B.Paste")
			(roundrect_rratio 0.25)
			(net 1 "GND")
			(pintype "passive")
		)
		(pad "2" smd roundrect
			(at 0.48 0 90)
			(size 0.59 0.64)
			(layers "B.Cu" "B.Mask" "B.Paste")
			(roundrect_rratio 0.25)
			(net 3 "+1V2")
			(pintype "passive")
		)
	)
)
